(kicad_pcb
	(version 20260206)
	(generator "pcbnew")
	(generator_version "10.0")
	(general
		(thickness 1.6)
		(legacy_teardrops no)
	)
	(paper "A4")
	(title_block
		(title "04192023_DAF0TMB3IC0_F0TG_MB_C_brd_V02_OCP.brd")
		(comment 1 "Grand Teton / footprints 4618-4624 of 8354")
	)
	(layers
		(0 "F.Cu" signal "TOP")
		(4 "In1.Cu" signal "GND")
		(6 "In2.Cu" signal "IN1")
		(8 "In3.Cu" signal "GND1")
		(10 "In4.Cu" signal "IN2")
		(12 "In5.Cu" signal "GND2")
		(14 "In6.Cu" signal "IN3")
		(16 "In7.Cu" signal "GND3")
		(18 "In8.Cu" signal "VCC")
		(20 "In9.Cu" signal "VCC1")
		(22 "In10.Cu" signal "GND4")
		(24 "In11.Cu" signal "IN4")
		(26 "In12.Cu" signal "GND5")
		(28 "In13.Cu" signal "IN5")
		(30 "In14.Cu" signal "GND6")
		(32 "In15.Cu" signal "IN6")
		(34 "In16.Cu" signal "GND7")
		(2 "B.Cu" signal "BOTTOM")
		(9 "F.Adhes" user "F.Adhesive")
		(11 "B.Adhes" user "B.Adhesive")
		(13 "F.Paste" user "Package Geometry/Pastemask Top")
		(15 "B.Paste" user "Package Geometry/Pastemask Bottom")
		(5 "F.SilkS" user "Ref Des/Silkscreen Top")
		(7 "B.SilkS" user "Ref Des/Silkscreen Bottom")
		(1 "F.Mask" user "Board Geometry/Soldermask Top")
		(3 "B.Mask" user "Board Geometry/Soldermask Bottom")
		(17 "Dwgs.User" user "User.Drawings")
		(19 "Cmts.User" user "User.Comments")
		(21 "Eco1.User" user "User.Eco1")
		(23 "Eco2.User" user "User.Eco2")
		(25 "Edge.Cuts" user "Board Geometry/Outline")
		(27 "Margin" user)
		(31 "F.CrtYd" user "Package Geometry/Place Bound Top")
		(29 "B.CrtYd" user "Package Geometry/Place Bound Bottom")
		(35 "F.Fab" user "Ref Des/Assembly Top")
		(33 "B.Fab" user "Ref Des/Assembly Bottom")
	)
	(footprint ""
		(layer "F.Cu")
		(at 136.50468 -29.01442 -90)
		(property "Reference" "R6194"
			(at 0 0 270)
			(layer "F.SilkS")
			(hide yes)
			(effects
				(font
					(size 1.27 1.27)
				)
			)
		)
		(property "Value" ""
			(at 0 0 270)
			(layer "F.Fab")
			(effects
				(font
					(size 1.27 1.27)
				)
			)
		)
		(duplicate_pad_numbers_are_jumpers no)
		(fp_line
			(start -0.32512 0.175006)
			(end -0.32512 -0.175006)
			(stroke
				(width 0.1)
				(type default)
			)
			(layer "F.Fab")
		)
		(fp_line
			(start 0.32512 0.175006)
			(end -0.32512 0.175006)
			(stroke
				(width 0.1)
				(type default)
			)
			(layer "F.Fab")
		)
		(fp_line
			(start -0.32512 -0.175006)
			(end 0.32512 -0.175006)
			(stroke
				(width 0.1)
				(type default)
			)
			(layer "F.Fab")
		)
		(fp_line
			(start 0.32512 -0.175006)
			(end 0.32512 0.175006)
			(stroke
				(width 0.1)
				(type default)
			)
			(layer "F.Fab")
		)
		(pad "1" smd rect
			(at -0.2667 0 270)
			(size 0.3048 0.381)
			(layers "F.Cu" "F.Mask" "F.Paste")
			(net "USB2_CPU0_P0_HUB1_R_DP")
		)
		(pad "2" smd rect
			(at 0.2667 0 90)
			(size 0.3048 0.381)
			(layers "F.Cu" "F.Mask" "F.Paste")
			(net "USB2_HUB_EXT_DP")
		)
	)
	(footprint ""
		(layer "F.Cu")
		(at 418.206936 -165.502082 -90)
		(property "Reference" "PR505"
			(at 0 0 270)
			(layer "F.SilkS")
			(hide yes)
			(effects
				(font
					(size 1.27 1.27)
				)
			)
		)
		(property "Value" ""
			(at 0 0 270)
			(layer "F.Fab")
			(effects
				(font
					(size 1.27 1.27)
				)
			)
		)
		(duplicate_pad_numbers_are_jumpers no)
		(fp_line
			(start -0.7874 0.4064)
			(end -0.7874 -0.4064)
			(stroke
				(width 0.1524)
				(type default)
			)
			(layer "F.SilkS")
		)
		(fp_line
			(start 0.7874 0.4064)
			(end -0.7874 0.4064)
			(stroke
				(width 0.1524)
				(type default)
			)
			(layer "F.SilkS")
		)
		(fp_line
			(start -0.7874 -0.4064)
			(end 0.7874 -0.4064)
			(stroke
				(width 0.1524)
				(type default)
			)
			(layer "F.SilkS")
		)
		(fp_line
			(start 0.7874 -0.4064)
			(end 0.7874 0.4064)
			(stroke
				(width 0.1524)
				(type default)
			)
			(layer "F.SilkS")
		)
		(fp_line
			(start -0.67945 0.3048)
			(end -0.67945 -0.305054)
			(stroke
				(width 0.1)
				(type default)
			)
			(layer "F.Fab")
		)
		(fp_line
			(start -0.12065 0.3048)
			(end -0.67945 0.3048)
			(stroke
				(width 0.1)
				(type default)
			)
			(layer "F.Fab")
		)
		(fp_line
			(start 0.120396 0.3048)
			(end 0.120396 0.2794)
			(stroke
				(width 0.1)
				(type default)
			)
			(layer "F.Fab")
		)
		(fp_line
			(start 0.67945 0.3048)
			(end 0.120396 0.3048)
			(stroke
				(width 0.1)
				(type default)
			)
			(layer "F.Fab")
		)
		(fp_line
			(start -0.12065 0.2794)
			(end -0.12065 0.3048)
			(stroke
				(width 0.1)
				(type default)
			)
			(layer "F.Fab")
		)
		(fp_line
			(start 0.120396 0.2794)
			(end -0.12065 0.2794)
			(stroke
				(width 0.1)
				(type default)
			)
			(layer "F.Fab")
		)
		(fp_line
			(start -0.12065 -0.2794)
			(end 0.12065 -0.2794)
			(stroke
				(width 0.1)
				(type default)
			)
			(layer "F.Fab")
		)
		(fp_line
			(start 0.12065 -0.2794)
			(end 0.12065 -0.3048)
			(stroke
				(width 0.1)
				(type default)
			)
			(layer "F.Fab")
		)
		(fp_line
			(start 0.12065 -0.3048)
			(end 0.67945 -0.3048)
			(stroke
				(width 0.1)
				(type default)
			)
			(layer "F.Fab")
		)
		(fp_line
			(start 0.67945 -0.3048)
			(end 0.67945 0.3048)
			(stroke
				(width 0.1)
				(type default)
			)
			(layer "F.Fab")
		)
		(fp_line
			(start -0.67945 -0.305054)
			(end -0.12065 -0.305054)
			(stroke
				(width 0.1)
				(type default)
			)
			(layer "F.Fab")
		)
		(fp_line
			(start -0.12065 -0.305054)
			(end -0.12065 -0.2794)
			(stroke
				(width 0.1)
				(type default)
			)
			(layer "F.Fab")
		)
		(pad "1" smd circle
			(at -0.40005 0 270)
			(size 0 0)
			(layers "F.Cu" "F.Mask" "F.Paste")
			(net "SW_PVDDCR_SOC_P0_SW3_RC")
		)
		(pad "2" smd circle
			(at 0.40005 0 270)
			(size 0 0)
			(layers "F.Cu" "F.Mask" "F.Paste")
			(net "GND")
		)
	)
	(footprint ""
		(layer "F.Cu")
		(at 327.881742 -393.9032 90)
		(property "Reference" "R964"
			(at 0 0 90)
			(layer "F.SilkS")
			(hide yes)
			(effects
				(font
					(size 1.27 1.27)
				)
			)
		)
		(property "Value" ""
			(at 0 0 90)
			(layer "F.Fab")
			(effects
				(font
					(size 1.27 1.27)
				)
			)
		)
		(duplicate_pad_numbers_are_jumpers no)
		(fp_line
			(start 0.32512 -0.175006)
			(end 0.32512 0.175006)
			(stroke
				(width 0.1)
				(type default)
			)
			(layer "F.Fab")
		)
		(fp_line
			(start -0.32512 -0.175006)
			(end 0.32512 -0.175006)
			(stroke
				(width 0.1)
				(type default)
			)
			(layer "F.Fab")
		)
		(fp_line
			(start 0.32512 0.175006)
			(end -0.32512 0.175006)
			(stroke
				(width 0.1)
				(type default)
			)
			(layer "F.Fab")
		)
		(fp_line
			(start -0.32512 0.175006)
			(end -0.32512 -0.175006)
			(stroke
				(width 0.1)
				(type default)
			)
			(layer "F.Fab")
		)
		(pad "1" smd rect
			(at -0.2667 0 90)
			(size 0.3048 0.381)
			(layers "F.Cu" "F.Mask" "F.Paste")
			(net "P1V8_CPU0_RT_1D")
		)
		(pad "2" smd rect
			(at 0.2667 0 270)
			(size 0.3048 0.381)
			(layers "F.Cu" "F.Mask" "F.Paste")
			(net "RT_CPU0_P0_ADDR3")
		)
	)
	(footprint ""
		(layer "F.Cu")
		(at 428.880016 -102.37724 -90)
		(property "Reference" "R3794"
			(at 0 0 270)
			(layer "F.SilkS")
			(hide yes)
			(effects
				(font
					(size 1.27 1.27)
				)
			)
		)
		(property "Value" ""
			(at 0 0 270)
			(layer "F.Fab")
			(effects
				(font
					(size 1.27 1.27)
				)
			)
		)
		(duplicate_pad_numbers_are_jumpers no)
		(fp_line
			(start -0.7874 0.4064)
			(end -0.7874 -0.4064)
			(stroke
				(width 0.1524)
				(type default)
			)
			(layer "F.SilkS")
		)
		(fp_line
			(start 0.7874 0.4064)
			(end -0.7874 0.4064)
			(stroke
				(width 0.1524)
				(type default)
			)
			(layer "F.SilkS")
		)
		(fp_line
			(start -0.7874 -0.4064)
			(end 0.7874 -0.4064)
			(stroke
				(width 0.1524)
				(type default)
			)
			(layer "F.SilkS")
		)
		(fp_line
			(start 0.7874 -0.4064)
			(end 0.7874 0.4064)
			(stroke
				(width 0.1524)
				(type default)
			)
			(layer "F.SilkS")
		)
		(fp_line
			(start -0.67945 0.3048)
			(end -0.67945 -0.305054)
			(stroke
				(width 0.1)
				(type default)
			)
			(layer "F.Fab")
		)
		(fp_line
			(start -0.12065 0.3048)
			(end -0.67945 0.3048)
			(stroke
				(width 0.1)
				(type default)
			)
			(layer "F.Fab")
		)
		(fp_line
			(start 0.120396 0.3048)
			(end 0.120396 0.2794)
			(stroke
				(width 0.1)
				(type default)
			)
			(layer "F.Fab")
		)
		(fp_line
			(start 0.67945 0.3048)
			(end 0.120396 0.3048)
			(stroke
				(width 0.1)
				(type default)
			)
			(layer "F.Fab")
		)
		(fp_line
			(start -0.12065 0.2794)
			(end -0.12065 0.3048)
			(stroke
				(width 0.1)
				(type default)
			)
			(layer "F.Fab")
		)
		(fp_line
			(start 0.120396 0.2794)
			(end -0.12065 0.2794)
			(stroke
				(width 0.1)
				(type default)
			)
			(layer "F.Fab")
		)
		(fp_line
			(start -0.12065 -0.2794)
			(end 0.12065 -0.2794)
			(stroke
				(width 0.1)
				(type default)
			)
			(layer "F.Fab")
		)
		(fp_line
			(start 0.12065 -0.2794)
			(end 0.12065 -0.3048)
			(stroke
				(width 0.1)
				(type default)
			)
			(layer "F.Fab")
		)
		(fp_line
			(start 0.12065 -0.3048)
			(end 0.67945 -0.3048)
			(stroke
				(width 0.1)
				(type default)
			)
			(layer "F.Fab")
		)
		(fp_line
			(start 0.67945 -0.3048)
			(end 0.67945 0.3048)
			(stroke
				(width 0.1)
				(type default)
			)
			(layer "F.Fab")
		)
		(fp_line
			(start -0.67945 -0.305054)
			(end -0.12065 -0.305054)
			(stroke
				(width 0.1)
				(type default)
			)
			(layer "F.Fab")
		)
		(fp_line
			(start -0.12065 -0.305054)
			(end -0.12065 -0.2794)
			(stroke
				(width 0.1)
				(type default)
			)
			(layer "F.Fab")
		)
		(pad "1" smd circle
			(at -0.40005 0 270)
			(size 0 0)
			(layers "F.Cu" "F.Mask" "F.Paste")
			(net "P3V3_OCP_PWRGD_1")
		)
		(pad "2" smd circle
			(at 0.40005 0 270)
			(size 0 0)
			(layers "F.Cu" "F.Mask" "F.Paste")
			(net "OCP_V3_1_P3V3_PWRGD")
		)
	)
	(footprint ""
		(layer "F.Cu")
		(at 190.119 -129.377948 90)
		(property "Reference" "R174"
			(at 0 0 90)
			(layer "F.SilkS")
			(hide yes)
			(effects
				(font
					(size 1.27 1.27)
				)
			)
		)
		(property "Value" ""
			(at 0 0 90)
			(layer "F.Fab")
			(effects
				(font
					(size 1.27 1.27)
				)
			)
		)
		(duplicate_pad_numbers_are_jumpers no)
		(fp_line
			(start 0.7874 -0.4064)
			(end 0.7874 0.4064)
			(stroke
				(width 0.1524)
				(type default)
			)
			(layer "F.SilkS")
		)
		(fp_line
			(start -0.7874 -0.4064)
			(end 0.7874 -0.4064)
			(stroke
				(width 0.1524)
				(type default)
			)
			(layer "F.SilkS")
		)
		(fp_line
			(start 0.7874 0.4064)
			(end -0.7874 0.4064)
			(stroke
				(width 0.1524)
				(type default)
			)
			(layer "F.SilkS")
		)
		(fp_line
			(start -0.7874 0.4064)
			(end -0.7874 -0.4064)
			(stroke
				(width 0.1524)
				(type default)
			)
			(layer "F.SilkS")
		)
		(fp_line
			(start -0.12065 -0.305054)
			(end -0.12065 -0.2794)
			(stroke
				(width 0.1)
				(type default)
			)
			(layer "F.Fab")
		)
		(fp_line
			(start -0.67945 -0.305054)
			(end -0.12065 -0.305054)
			(stroke
				(width 0.1)
				(type default)
			)
			(layer "F.Fab")
		)
		(fp_line
			(start 0.67945 -0.3048)
			(end 0.67945 0.3048)
			(stroke
				(width 0.1)
				(type default)
			)
			(layer "F.Fab")
		)
		(fp_line
			(start 0.12065 -0.3048)
			(end 0.67945 -0.3048)
			(stroke
				(width 0.1)
				(type default)
			)
			(layer "F.Fab")
		)
		(fp_line
			(start 0.12065 -0.2794)
			(end 0.12065 -0.3048)
			(stroke
				(width 0.1)
				(type default)
			)
			(layer "F.Fab")
		)
		(fp_line
			(start -0.12065 -0.2794)
			(end 0.12065 -0.2794)
			(stroke
				(width 0.1)
				(type default)
			)
			(layer "F.Fab")
		)
		(fp_line
			(start 0.120396 0.2794)
			(end -0.12065 0.2794)
			(stroke
				(width 0.1)
				(type default)
			)
			(layer "F.Fab")
		)
		(fp_line
			(start -0.12065 0.2794)
			(end -0.12065 0.3048)
			(stroke
				(width 0.1)
				(type default)
			)
			(layer "F.Fab")
		)
		(fp_line
			(start 0.67945 0.3048)
			(end 0.120396 0.3048)
			(stroke
				(width 0.1)
				(type default)
			)
			(layer "F.Fab")
		)
		(fp_line
			(start 0.120396 0.3048)
			(end 0.120396 0.2794)
			(stroke
				(width 0.1)
				(type default)
			)
			(layer "F.Fab")
		)
		(fp_line
			(start -0.12065 0.3048)
			(end -0.67945 0.3048)
			(stroke
				(width 0.1)
				(type default)
			)
			(layer "F.Fab")
		)
		(fp_line
			(start -0.67945 0.3048)
			(end -0.67945 -0.305054)
			(stroke
				(width 0.1)
				(type default)
			)
			(layer "F.Fab")
		)
		(pad "1" smd circle
			(at -0.40005 0 90)
			(size 0 0)
			(layers "F.Cu" "F.Mask" "F.Paste")
			(net "SCM_IRQ_1V8_R_N")
		)
		(pad "2" smd circle
			(at 0.40005 0 90)
			(size 0 0)
			(layers "F.Cu" "F.Mask" "F.Paste")
			(net "SCM_IRQ_1V8_N")
		)
	)
	(footprint ""
		(layer "F.Cu")
		(at 21.181314 -95.510604)
		(property "Reference" "R3664"
			(at 0 0 0)
			(layer "F.SilkS")
			(hide yes)
			(effects
				(font
					(size 1.27 1.27)
				)
			)
		)
		(property "Value" ""
			(at 0 0 0)
			(layer "F.Fab")
			(effects
				(font
					(size 1.27 1.27)
				)
			)
		)
		(duplicate_pad_numbers_are_jumpers no)
		(fp_line
			(start -0.7874 -0.4064)
			(end 0.7874 -0.4064)
			(stroke
				(width 0.1524)
				(type default)
			)
			(layer "F.SilkS")
		)
		(fp_line
			(start -0.7874 0.4064)
			(end -0.7874 -0.4064)
			(stroke
				(width 0.1524)
				(type default)
			)
			(layer "F.SilkS")
		)
		(fp_line
			(start 0.7874 -0.4064)
			(end 0.7874 0.4064)
			(stroke
				(width 0.1524)
				(type default)
			)
			(layer "F.SilkS")
		)
		(fp_line
			(start 0.7874 0.4064)
			(end -0.7874 0.4064)
			(stroke
				(width 0.1524)
				(type default)
			)
			(layer "F.SilkS")
		)
		(fp_line
			(start -0.67945 -0.305054)
			(end -0.12065 -0.305054)
			(stroke
				(width 0.1)
				(type default)
			)
			(layer "F.Fab")
		)
		(fp_line
			(start -0.67945 0.3048)
			(end -0.67945 -0.305054)
			(stroke
				(width 0.1)
				(type default)
			)
			(layer "F.Fab")
		)
		(fp_line
			(start -0.12065 -0.305054)
			(end -0.12065 -0.2794)
			(stroke
				(width 0.1)
				(type default)
			)
			(layer "F.Fab")
		)
		(fp_line
			(start -0.12065 -0.2794)
			(end 0.12065 -0.2794)
			(stroke
				(width 0.1)
				(type default)
			)
			(layer "F.Fab")
		)
		(fp_line
			(start -0.12065 0.2794)
			(end -0.12065 0.3048)
			(stroke
				(width 0.1)
				(type default)
			)
			(layer "F.Fab")
		)
		(fp_line
			(start -0.12065 0.3048)
			(end -0.67945 0.3048)
			(stroke
				(width 0.1)
				(type default)
			)
			(layer "F.Fab")
		)
		(fp_line
			(start 0.120396 0.2794)
			(end -0.12065 0.2794)
			(stroke
				(width 0.1)
				(type default)
			)
			(layer "F.Fab")
		)
		(fp_line
			(start 0.120396 0.3048)
			(end 0.120396 0.2794)
			(stroke
				(width 0.1)
				(type default)
			)
			(layer "F.Fab")
		)
		(fp_line
			(start 0.12065 -0.3048)
			(end 0.67945 -0.3048)
			(stroke
				(width 0.1)
				(type default)
			)
			(layer "F.Fab")
		)
		(fp_line
			(start 0.12065 -0.2794)
			(end 0.12065 -0.3048)
			(stroke
				(width 0.1)
				(type default)
			)
			(layer "F.Fab")
		)
		(fp_line
			(start 0.67945 -0.3048)
			(end 0.67945 0.3048)
			(stroke
				(width 0.1)
				(type default)
			)
			(layer "F.Fab")
		)
		(fp_line
			(start 0.67945 0.3048)
			(end 0.120396 0.3048)
			(stroke
				(width 0.1)
				(type default)
			)
			(layer "F.Fab")
		)
		(pad "1" smd circle
			(at -0.40005 0)
			(size 0 0)
			(layers "F.Cu" "F.Mask" "F.Paste")
			(net "USB_HUB_PSELF")
		)
		(pad "2" smd circle
			(at 0.40005 0)
			(size 0 0)
			(layers "F.Cu" "F.Mask" "F.Paste")
			(net "GND")
		)
	)
	(footprint ""
		(layer "F.Cu")
		(at 341.33536 -15.979394 90)
		(property "Reference" "R950"
			(at 0 0 90)
			(layer "F.SilkS")
			(hide yes)
			(effects
				(font
					(size 1.27 1.27)
				)
			)
		)
		(property "Value" ""
			(at 0 0 90)
			(layer "F.Fab")
			(effects
				(font
					(size 1.27 1.27)
				)
			)
		)
		(duplicate_pad_numbers_are_jumpers no)
		(fp_line
			(start 0.7874 -0.4064)
			(end 0.7874 0.4064)
			(stroke
				(width 0.1524)
				(type default)
			)
			(layer "F.SilkS")
		)
		(fp_line
			(start -0.7874 -0.4064)
			(end 0.7874 -0.4064)
			(stroke
				(width 0.1524)
				(type default)
			)
			(layer "F.SilkS")
		)
		(fp_line
			(start 0.7874 0.4064)
			(end -0.7874 0.4064)
			(stroke
				(width 0.1524)
				(type default)
			)
			(layer "F.SilkS")
		)
		(fp_line
			(start -0.7874 0.4064)
			(end -0.7874 -0.4064)
			(stroke
				(width 0.1524)
				(type default)
			)
			(layer "F.SilkS")
		)
		(fp_line
			(start -0.12065 -0.305054)
			(end -0.12065 -0.2794)
			(stroke
				(width 0.1)
				(type default)
			)
			(layer "F.Fab")
		)
		(fp_line
			(start -0.67945 -0.305054)
			(end -0.12065 -0.305054)
			(stroke
				(width 0.1)
				(type default)
			)
			(layer "F.Fab")
		)
		(fp_line
			(start 0.67945 -0.3048)
			(end 0.67945 0.3048)
			(stroke
				(width 0.1)
				(type default)
			)
			(layer "F.Fab")
		)
		(fp_line
			(start 0.12065 -0.3048)
			(end 0.67945 -0.3048)
			(stroke
				(width 0.1)
				(type default)
			)
			(layer "F.Fab")
		)
		(fp_line
			(start 0.12065 -0.2794)
			(end 0.12065 -0.3048)
			(stroke
				(width 0.1)
				(type default)
			)
			(layer "F.Fab")
		)
		(fp_line
			(start -0.12065 -0.2794)
			(end 0.12065 -0.2794)
			(stroke
				(width 0.1)
				(type default)
			)
			(layer "F.Fab")
		)
		(fp_line
			(start 0.120396 0.2794)
			(end -0.12065 0.2794)
			(stroke
				(width 0.1)
				(type default)
			)
			(layer "F.Fab")
		)
		(fp_line
			(start -0.12065 0.2794)
			(end -0.12065 0.3048)
			(stroke
				(width 0.1)
				(type default)
			)
			(layer "F.Fab")
		)
		(fp_line
			(start 0.67945 0.3048)
			(end 0.120396 0.3048)
			(stroke
				(width 0.1)
				(type default)
			)
			(layer "F.Fab")
		)
		(fp_line
			(start 0.120396 0.3048)
			(end 0.120396 0.2794)
			(stroke
				(width 0.1)
				(type default)
			)
			(layer "F.Fab")
		)
		(fp_line
			(start -0.12065 0.3048)
			(end -0.67945 0.3048)
			(stroke
				(width 0.1)
				(type default)
			)
			(layer "F.Fab")
		)
		(fp_line
			(start -0.67945 0.3048)
			(end -0.67945 -0.305054)
			(stroke
				(width 0.1)
				(type default)
			)
			(layer "F.Fab")
		)
		(pad "1" smd circle
			(at -0.40005 0 90)
			(size 0 0)
			(layers "F.Cu" "F.Mask" "F.Paste")
			(net "PU_SMERR_LED")
		)
		(pad "2" smd circle
			(at 0.40005 0 90)
			(size 0 0)
			(layers "F.Cu" "F.Mask" "F.Paste")
			(net "P3V3_AUX")
		)
	)
)
